(kicad_pcb
	(version 20241229)
	(generator "pcbnew")
	(generator_version "9.0")
	(general
		(thickness 1.294)
		(legacy_teardrops no)
	)
	(paper "A3")
	(title_block
		(title "Kintex 410T devboard")
		(date "2024-04-03")
		(rev "1.1.2")
		(comment 9 "footprints 428-432 of 975")
	)
	(layers
		(0 "F.Cu" mixed)
		(4 "In1.Cu" power)
		(6 "In2.Cu" power)
		(8 "In3.Cu" mixed)
		(10 "In4.Cu" power)
		(12 "In5.Cu" mixed)
		(14 "In6.Cu" power)
		(16 "In7.Cu" mixed)
		(18 "In8.Cu" power)
		(2 "B.Cu" mixed)
		(9 "F.Adhes" user "F.Adhesive")
		(11 "B.Adhes" user "B.Adhesive")
		(13 "F.Paste" user)
		(15 "B.Paste" user)
		(5 "F.SilkS" user "F.Silkscreen")
		(7 "B.SilkS" user "B.Silkscreen")
		(1 "F.Mask" user)
		(3 "B.Mask" user)
		(17 "Dwgs.User" user "User.Drawings")
		(19 "Cmts.User" user "User.Comments")
		(21 "Eco1.User" user "User.Eco1")
		(23 "Eco2.User" user "User.Eco2")
		(25 "Edge.Cuts" user)
		(27 "Margin" user)
		(31 "F.CrtYd" user "F.Courtyard")
		(29 "B.CrtYd" user "B.Courtyard")
		(35 "F.Fab" user)
		(33 "B.Fab" user)
	)
	(footprint "antmicro-footprints:R_0402_1005Metric"
		(layer "F.Cu")
		(at 173.570001 105.523751)
		(descr "Resistor SMD 0402")
		(tags "resistor SMD 0402")
		(property "Reference" "R271"
			(at 0.929999 0.376249 0)
			(layer "F.SilkS")
			(effects
				(font
					(size 0.7 0.7)
					(thickness 0.15)
				)
				(justify left bottom)
			)
		)
		(property "Value" "R_33R_0402"
			(at 0 1.4 0)
			(layer "F.Fab")
			(effects
				(font
					(size 0.7 0.7)
					(thickness 0.15)
				)
				(justify left bottom)
			)
		)
		(property "Description" "SMD Chip Resistor, 33 ohm, ± 1%, 62.5 mW, 0402 [1005 Metric], Thick Film, General Purpose"
			(at 0 0 0)
			(layer "F.Fab")
			(hide yes)
			(effects
				(font
					(size 1.27 1.27)
					(thickness 0.15)
				)
			)
		)
		(property "Author" "Antmicro"
			(at 0 0 0)
			(layer "F.Fab")
			(hide yes)
			(effects
				(font
					(size 1 1)
					(thickness 0.15)
				)
			)
		)
		(property "License" "Apache-2.0"
			(at 0 0 0)
			(layer "F.Fab")
			(hide yes)
			(effects
				(font
					(size 1 1)
					(thickness 0.15)
				)
			)
		)
		(property "MPN" "CR0402-FX-33R0GLF"
			(at 0 0 0)
			(layer "F.Fab")
			(hide yes)
			(effects
				(font
					(size 1 1)
					(thickness 0.15)
				)
			)
		)
		(property "Manufacturer" "Bourns"
			(at 0 0 0)
			(layer "F.Fab")
			(hide yes)
			(effects
				(font
					(size 1 1)
					(thickness 0.15)
				)
			)
		)
		(property "Tolerance" "1%"
			(at 0 0 0)
			(layer "F.Fab")
			(hide yes)
			(effects
				(font
					(size 1 1)
					(thickness 0.15)
				)
			)
		)
		(property "Val" "33R"
			(at 0 0 0)
			(layer "F.Fab")
			(hide yes)
			(effects
				(font
					(size 1 1)
					(thickness 0.15)
				)
			)
		)
		(sheetname "FMC+ HSPC")
		(sheetfile "fmc-hspc.kicad_sch")
		(attr smd)
		(fp_rect
			(start -0.925 -0.47)
			(end 0.925 0.47)
			(stroke
				(width 0.05)
				(type default)
			)
			(fill no)
			(layer "F.CrtYd")
		)
		(fp_rect
			(start -0.5 -0.25)
			(end 0.5 0.25)
			(stroke
				(width 0.15)
				(type solid)
			)
			(fill no)
			(layer "F.Fab")
		)
		(pad "1" smd roundrect
			(at -0.48 0)
			(size 0.59 0.64)
			(layers "F.Cu" "F.Mask" "F.Paste")
			(roundrect_rratio 0.25)
			(net 499 "/FMC+ HSPC/GTR_REFCLK1_R_P")
			(pintype "passive")
		)
		(pad "2" smd roundrect
			(at 0.48 0)
			(size 0.59 0.64)
			(layers "F.Cu" "F.Mask" "F.Paste")
			(roundrect_rratio 0.25)
			(net 591 "/FMC+ HSPC/GTX115.REFCLK1_P")
			(pintype "passive")
		)
	)
	(footprint "antmicro-footprints:R_0402_1005Metric"
		(layer "F.Cu")
		(at 158 184 -90)
		(descr "Resistor SMD 0402")
		(tags "resistor SMD 0402")
		(property "Reference" "R367"
			(at -0.7 -0.4 270)
			(layer "F.SilkS")
			(effects
				(font
					(size 0.7 0.7)
					(thickness 0.15)
				)
				(justify left bottom)
			)
		)
		(property "Value" "R_47k_0402"
			(at 0 1.4 270)
			(layer "F.Fab")
			(effects
				(font
					(size 0.7 0.7)
					(thickness 0.15)
				)
				(justify left bottom)
			)
		)
		(property "Description" "SMD Chip Resistor, 47 kohm, ± 1%, 62.5 mW, 0402 [1005 Metric], Thick Film, General Purpose"
			(at 0 0 270)
			(layer "F.Fab")
			(hide yes)
			(effects
				(font
					(size 1.27 1.27)
					(thickness 0.15)
				)
			)
		)
		(property "Author" "Antmicro"
			(at -26 342 0)
			(layer "F.Fab")
			(hide yes)
			(effects
				(font
					(size 1 1)
					(thickness 0.15)
				)
			)
		)
		(property "License" "Apache-2.0"
			(at -26 342 0)
			(layer "F.Fab")
			(hide yes)
			(effects
				(font
					(size 1 1)
					(thickness 0.15)
				)
			)
		)
		(property "MPN" "CR0402-FX-4702GLF"
			(at -26 342 0)
			(layer "F.Fab")
			(hide yes)
			(effects
				(font
					(size 1 1)
					(thickness 0.15)
				)
			)
		)
		(property "Manufacturer" "Bourns"
			(at -26 342 0)
			(layer "F.Fab")
			(hide yes)
			(effects
				(font
					(size 1 1)
					(thickness 0.15)
				)
			)
		)
		(property "Tolerance" "1%"
			(at -26 342 0)
			(layer "F.Fab")
			(hide yes)
			(effects
				(font
					(size 1 1)
					(thickness 0.15)
				)
			)
		)
		(property "Val" "47k"
			(at -26 342 0)
			(layer "F.Fab")
			(hide yes)
			(effects
				(font
					(size 1 1)
					(thickness 0.15)
				)
			)
		)
		(sheetname "DC-DC Converters")
		(sheetfile "dc-dc.kicad_sch")
		(attr smd)
		(fp_rect
			(start -0.925 -0.47)
			(end 0.925 0.47)
			(stroke
				(width 0.05)
				(type default)
			)
			(fill no)
			(layer "F.CrtYd")
		)
		(fp_rect
			(start -0.5 -0.25)
			(end 0.5 0.25)
			(stroke
				(width 0.15)
				(type solid)
			)
			(fill no)
			(layer "F.Fab")
		)
		(pad "1" smd roundrect
			(at -0.48 0 270)
			(size 0.59 0.64)
			(layers "F.Cu" "F.Mask" "F.Paste")
			(roundrect_rratio 0.25)
			(net 974 "/DC-DC Converters/~{PB_CTRL_IN}")
			(pintype "passive")
		)
		(pad "2" smd roundrect
			(at 0.48 0 270)
			(size 0.59 0.64)
			(layers "F.Cu" "F.Mask" "F.Paste")
			(roundrect_rratio 0.25)
			(net 37 "+3V3_AON")
			(pintype "passive")
		)
	)
	(footprint "antmicro-footprints:SOT-23-6"
		(layer "F.Cu")
		(at 189.425 183.798999 90)
		(property "Reference" "U9"
			(at 0.898999 -3.325 180)
			(layer "F.SilkS")
			(effects
				(font
					(size 0.7 0.7)
					(thickness 0.15)
				)
				(justify left bottom)
			)
		)
		(property "Value" "LTC4412IS6"
			(at -1.75 2.75 90)
			(layer "F.Fab")
			(effects
				(font
					(size 0.7 0.7)
					(thickness 0.15)
				)
				(justify left bottom)
			)
		)
		(property "Description" "Ideal diode controller"
			(at 0 0 90)
			(layer "F.Fab")
			(hide yes)
			(effects
				(font
					(size 1.27 1.27)
					(thickness 0.15)
				)
			)
		)
		(property "Author" "Antmicro"
			(at 373.223999 -5.626001 0)
			(layer "F.Fab")
			(hide yes)
			(effects
				(font
					(size 1 1)
					(thickness 0.15)
				)
			)
		)
		(property "License" "Apache-2.0"
			(at 373.223999 -5.626001 0)
			(layer "F.Fab")
			(hide yes)
			(effects
				(font
					(size 1 1)
					(thickness 0.15)
				)
			)
		)
		(property "MPN" "LTC4412IS6#TRMPBF"
			(at 373.223999 -5.626001 0)
			(layer "F.Fab")
			(hide yes)
			(effects
				(font
					(size 1 1)
					(thickness 0.15)
				)
			)
		)
		(property "Manufacturer" "Analog Devices"
			(at 373.223999 -5.626001 0)
			(layer "F.Fab")
			(hide yes)
			(effects
				(font
					(size 1 1)
					(thickness 0.15)
				)
			)
		)
		(sheetname "Power supply")
		(sheetfile "power-supply.kicad_sch")
		(attr smd)
		(fp_line
			(start 1.45 -0.7)
			(end 1.45 -0.4)
			(stroke
				(width 0.12)
				(type solid)
			)
			(layer "F.SilkS")
		)
		(fp_line
			(start 1.3 -0.7)
			(end 1.45 -0.7)
			(stroke
				(width 0.12)
				(type solid)
			)
			(layer "F.SilkS")
		)
		(fp_line
			(start -1.3 -0.7)
			(end -1.45 -0.7)
			(stroke
				(width 0.12)
				(type solid)
			)
			(layer "F.SilkS")
		)
		(fp_line
			(start -1.45 -0.7)
			(end -1.45 -0.4)
			(stroke
				(width 0.12)
				(type solid)
			)
			(layer "F.SilkS")
		)
		(fp_line
			(start 1.45 0.7)
			(end 1.45 0.4)
			(stroke
				(width 0.12)
				(type solid)
			)
			(layer "F.SilkS")
		)
		(fp_line
			(start 1.3 0.7)
			(end 1.45 0.7)
			(stroke
				(width 0.12)
				(type solid)
			)
			(layer "F.SilkS")
		)
		(fp_line
			(start -1.45 0.7)
			(end -1.45 0.4)
			(stroke
				(width 0.12)
				(type solid)
			)
			(layer "F.SilkS")
		)
		(fp_rect
			(start -1.55 -1.85)
			(end 1.55 1.75)
			(stroke
				(width 0.05)
				(type solid)
			)
			(fill no)
			(layer "F.CrtYd")
		)
		(fp_line
			(start 1.5 -0.7)
			(end 1.5 0.7)
			(stroke
				(width 0.1)
				(type solid)
			)
			(layer "F.Fab")
		)
		(fp_line
			(start -1.5 -0.7)
			(end 1.5 -0.7)
			(stroke
				(width 0.1)
				(type solid)
			)
			(layer "F.Fab")
		)
		(fp_line
			(start 1.5 0.7)
			(end -1.5 0.7)
			(stroke
				(width 0.1)
				(type solid)
			)
			(layer "F.Fab")
		)
		(fp_line
			(start -1.5 0.7)
			(end -1.5 -0.7)
			(stroke
				(width 0.1)
				(type solid)
			)
			(layer "F.Fab")
		)
		(fp_text user "."
			(at -1.4 1.2 270)
			(layer "F.SilkS")
			(effects
				(font
					(size 1 1)
					(thickness 0.15)
				)
			)
		)
		(pad "1" smd roundrect
			(at -0.954 1.1 90)
			(size 0.55 1)
			(layers "F.Cu" "F.Mask" "F.Paste")
			(roundrect_rratio 0.15)
			(net 4 "/Power supply/DC_IN")
			(pinfunction "IN")
			(pintype "power_in")
		)
		(pad "2" smd roundrect
			(at -0.003 1.1 90)
			(size 0.55 1)
			(layers "F.Cu" "F.Mask" "F.Paste")
			(roundrect_rratio 0.15)
			(net 1 "GND")
			(pinfunction "GND")
			(pintype "power_in")
		)
		(pad "3" smd roundrect
			(at 0.947 1.1 90)
			(size 0.55 1)
			(layers "F.Cu" "F.Mask" "F.Paste")
			(roundrect_rratio 0.15)
			(net 1 "GND")
			(pinfunction "CTL")
			(pintype "input")
		)
		(pad "4" smd roundrect
			(at 0.947 -1.214 90)
			(size 0.55 1)
			(layers "F.Cu" "F.Mask" "F.Paste")
			(roundrect_rratio 0.15)
			(net 1156 "unconnected-(U9-STAT-Pad4)")
			(pinfunction "STAT")
			(pintype "output+no_connect")
		)
		(pad "5" smd roundrect
			(at -0.003 -1.214 90)
			(size 0.55 1)
			(layers "F.Cu" "F.Mask" "F.Paste")
			(roundrect_rratio 0.15)
			(net 338 "Net-(Q5-G)")
			(pinfunction "GATE")
			(pintype "output")
		)
		(pad "6" smd roundrect
			(at -0.954 -1.214 90)
			(size 0.55 1)
			(layers "F.Cu" "F.Mask" "F.Paste")
			(roundrect_rratio 0.15)
			(net 702 "VDC")
			(pinfunction "SENSE")
			(pintype "input")
		)
	)
	(footprint "antmicro-footprints:LED_0603_1608Metric_B"
		(layer "F.Cu")
		(at 261.5 81.4)
		(descr "LED SMD 0603 Blue")
		(tags "LED SMD 0603 Blue")
		(property "Reference" "D25"
			(at -1.1 1.5 0)
			(layer "F.SilkS")
			(effects
				(font
					(size 0.7 0.7)
					(thickness 0.15)
				)
				(justify left bottom)
			)
		)
		(property "Value" "LED_B_0603_KP-1608QBC-D"
			(at 0 1.6 0)
			(layer "F.Fab")
			(effects
				(font
					(size 0.7 0.7)
					(thickness 0.15)
				)
				(justify left bottom)
			)
		)
		(property "Description" "LED, Blue, SMD, 0603, 20 mA, 3.3 V, 465 nm"
			(at 0 0 0)
			(layer "F.Fab")
			(hide yes)
			(effects
				(font
					(size 1.27 1.27)
					(thickness 0.15)
				)
			)
		)
		(property "Author" "Antmicro"
			(at 0 0 0)
			(layer "F.Fab")
			(hide yes)
			(effects
				(font
					(size 1 1)
					(thickness 0.15)
				)
			)
		)
		(property "Color" "Blue"
			(at 0 0 0)
			(layer "F.Fab")
			(hide yes)
			(effects
				(font
					(size 1 1)
					(thickness 0.15)
				)
			)
		)
		(property "License" "Apache-2.0"
			(at 0 0 0)
			(layer "F.Fab")
			(hide yes)
			(effects
				(font
					(size 1 1)
					(thickness 0.15)
				)
			)
		)
		(property "MPN" "KP-1608QBC-D"
			(at 0 0 0)
			(layer "F.Fab")
			(hide yes)
			(effects
				(font
					(size 1 1)
					(thickness 0.15)
				)
			)
		)
		(property "Manufacturer" "Kingbright"
			(at 0 0 0)
			(layer "F.Fab")
			(hide yes)
			(effects
				(font
					(size 1 1)
					(thickness 0.15)
				)
			)
		)
		(property "Public" "False"
			(at 0 0 0)
			(layer "F.Fab")
			(hide yes)
			(effects
				(font
					(size 1 1)
					(thickness 0.15)
				)
			)
		)
		(sheetname "User GPIO + LED + button + DIP switch")
		(sheetfile "user-gpio.kicad_sch")
		(attr smd)
		(fp_line
			(start -1.18 -0.319)
			(end -1.18 0.321)
			(stroke
				(width 0.15)
				(type solid)
			)
			(layer "F.SilkS")
		)
		(fp_line
			(start -0.094672 0.001008)
			(end -0.24 0.001008)
			(stroke
				(width 0.1)
				(type solid)
			)
			(layer "F.SilkS")
		)
		(fp_line
			(start -0.094672 0.001008)
			(end 0.105328 -0.198992)
			(stroke
				(width 0.1)
				(type solid)
			)
			(layer "F.SilkS")
		)
		(fp_line
			(start -0.094672 0.201008)
			(end -0.094672 -0.198992)
			(stroke
				(width 0.1)
				(type solid)
			)
			(layer "F.SilkS")
		)
		(fp_line
			(start 0.105328 0.001008)
			(end 0.24 0.001)
			(stroke
				(width 0.1)
				(type solid)
			)
			(layer "F.SilkS")
		)
		(fp_line
			(start 0.105328 0.201008)
			(end -0.094672 0.001008)
			(stroke
				(width 0.1)
				(type solid)
			)
			(layer "F.SilkS")
		)
		(fp_line
			(start 0.105328 0.201008)
			(end 0.105328 -0.198992)
			(stroke
				(width 0.1)
				(type solid)
			)
			(layer "F.SilkS")
		)
		(fp_line
			(start 0.22 -0.35)
			(end -0.22 -0.35)
			(stroke
				(width 0.15)
				(type solid)
			)
			(layer "F.SilkS")
		)
		(fp_line
			(start 0.22 0.35)
			(end -0.22 0.35)
			(stroke
				(width 0.15)
				(type solid)
			)
			(layer "F.SilkS")
		)
		(fp_rect
			(start 1.25 0.65)
			(end -1.25 -0.65)
			(stroke
				(width 0.05)
				(type solid)
			)
			(fill no)
			(layer "F.CrtYd")
		)
		(fp_line
			(start -0.199 -0.202)
			(end -0.199 0.1)
			(stroke
				(width 0.15)
				(type solid)
			)
			(layer "F.Fab")
		)
		(fp_line
			(start -0.199 0)
			(end -0.597 0)
			(stroke
				(width 0.15)
				(type solid)
			)
			(layer "F.Fab")
		)
		(fp_line
			(start -0.199 0.2)
			(end -0.199 0.1)
			(stroke
				(width 0.15)
				(type solid)
			)
			(layer "F.Fab")
		)
		(fp_line
			(start -0.101 0)
			(end 0.201 0.2)
			(stroke
				(width 0.15)
				(type solid)
			)
			(layer "F.Fab")
		)
		(fp_line
			(start 0.201 -0.202)
			(end -0.101 0)
			(stroke
				(width 0.15)
				(type solid)
			)
			(layer "F.Fab")
		)
		(fp_line
			(start 0.201 0)
			(end 0.201 -0.202)
			(stroke
				(width 0.15)
				(type solid)
			)
			(layer "F.Fab")
		)
		(fp_line
			(start 0.201 0.2)
			(end 0.201 0)
			(stroke
				(width 0.15)
				(type solid)
			)
			(layer "F.Fab")
		)
		(fp_line
			(start 0.599 0)
			(end 0.201 0)
			(stroke
				(width 0.15)
				(type solid)
			)
			(layer "F.Fab")
		)
		(fp_rect
			(start 0.848 0.4)
			(end -0.85 -0.402)
			(stroke
				(width 0.15)
				(type solid)
			)
			(fill no)
			(layer "F.Fab")
		)
		(pad "1" smd roundrect
			(at -0.7 0 180)
			(size 0.8 1)
			(layers "F.Cu" "F.Mask" "F.Paste")
			(roundrect_rratio 0.2)
			(net 787 "Net-(D25-C)")
			(pinfunction "C")
			(pintype "passive")
		)
		(pad "2" smd roundrect
			(at 0.7 0 180)
			(size 0.8 1)
			(layers "F.Cu" "F.Mask" "F.Paste")
			(roundrect_rratio 0.2)
			(net 789 "Net-(D25-A)")
			(pinfunction "A")
			(pintype "passive")
		)
	)
	(footprint "antmicro-footprints:R_0402_1005Metric"
		(layer "F.Cu")
		(at 244.15 106.8)
		(descr "Resistor SMD 0402")
		(tags "resistor SMD 0402")
		(property "Reference" "R259"
			(at 0.8 0.35 0)
			(layer "F.SilkS")
			(effects
				(font
					(size 0.7 0.7)
					(thickness 0.15)
				)
				(justify left bottom)
			)
		)
		(property "Value" "R_0R_0402"
			(at 0 1.4 0)
			(layer "F.Fab")
			(effects
				(font
					(size 0.7 0.7)
					(thickness 0.15)
				)
				(justify left bottom)
			)
		)
		(property "Description" "SMD Chip Resistor, Jumper, 0 ohm, 100 mW, 0402 [1005 Metric], Thick Film, General Purpose"
			(at 0 0 0)
			(layer "F.Fab")
			(hide yes)
			(effects
				(font
					(size 1.27 1.27)
					(thickness 0.15)
				)
			)
		)
		(property "Author" "Antmicro"
			(at 0 0 0)
			(layer "F.Fab")
			(hide yes)
			(effects
				(font
					(size 1 1)
					(thickness 0.15)
				)
			)
		)
		(property "Current" "1A"
			(at 0 0 0)
			(layer "F.Fab")
			(hide yes)
			(effects
				(font
					(size 1 1)
					(thickness 0.15)
				)
			)
		)
		(property "License" "Apache-2.0"
			(at 0 0 0)
			(layer "F.Fab")
			(hide yes)
			(effects
				(font
					(size 1 1)
					(thickness 0.15)
				)
			)
		)
		(property "MPN" "ERJ2GE0R00X"
			(at 0 0 0)
			(layer "F.Fab")
			(hide yes)
			(effects
				(font
					(size 1 1)
					(thickness 0.15)
				)
			)
		)
		(property "Manufacturer" "Panasonic"
			(at 0 0 0)
			(layer "F.Fab")
			(hide yes)
			(effects
				(font
					(size 1 1)
					(thickness 0.15)
				)
			)
		)
		(property "Tolerance" ""
			(at 0 0 0)
			(layer "F.Fab")
			(hide yes)
			(effects
				(font
					(size 1 1)
					(thickness 0.15)
				)
			)
		)
		(property "Val" "0R"
			(at 0 0 0)
			(layer "F.Fab")
			(hide yes)
			(effects
				(font
					(size 1 1)
					(thickness 0.15)
				)
			)
		)
		(sheetname "HDMI + Ethernet")
		(sheetfile "hdmi-ethernet.kicad_sch")
		(attr smd)
		(fp_rect
			(start -0.925 -0.47)
			(end 0.925 0.47)
			(stroke
				(width 0.05)
				(type default)
			)
			(fill no)
			(layer "F.CrtYd")
		)
		(fp_rect
			(start -0.5 -0.25)
			(end 0.5 0.25)
			(stroke
				(width 0.15)
				(type solid)
			)
			(fill no)
			(layer "F.Fab")
		)
		(pad "1" smd roundrect
			(at -0.48 0)
			(size 0.59 0.64)
			(layers "F.Cu" "F.Mask" "F.Paste")
			(roundrect_rratio 0.25)
			(net 529 "/FPGA Bank 16 & 17/HDMI.D0_N")
			(pintype "passive")
		)
		(pad "2" smd roundrect
			(at 0.48 0)
			(size 0.59 0.64)
			(layers "F.Cu" "F.Mask" "F.Paste")
			(roundrect_rratio 0.25)
			(net 862 "/HDMI + Ethernet/HDMI_CONN_D0_N")
			(pintype "passive")
		)
	)
)
